# S9S_MB_2U (Grand Teton) — schematic netlist excerpt (pin names and nets, part order shuffled) for the footprints in the layout excerpt that follows; sources: Cadence DE-HDL packaged netlist, KiCad conversion of 03242023_DA0F0TMBIJ0_F0T_Motherboard_J_brd_V01_OCP.brd

R2385  Q_RES  2K 1% CHIP  pkg 0402LF  page 300 : A = FM_PVNN_MAIN_CPU1_EN ; B = GND
PC572_P1_1  Q_CAP  100NF 50V 10% X7R  pkg C0402  page 285 : A = PVCCIN_CPU1 ; B = GND

(kicad_pcb
	(version 20260206)
	(generator "pcbnew")
	(generator_version "10.0")
	(general
		(thickness 1.6)
		(legacy_teardrops no)
	)
	(paper "A4")
	(title_block
		(title "03242023_DA0F0TMBIJ0_F0T_Motherboard_J_brd_V01_OCP.brd")
		(comment 1 "Grand Teton / footprints 5988-5989 of 6105")
	)
	(layers
		(0 "F.Cu" signal "TOP")
		(4 "In1.Cu" signal "GND")
		(6 "In2.Cu" signal "IN1")
		(8 "In3.Cu" signal "GND1")
		(10 "In4.Cu" signal "IN2")
		(12 "In5.Cu" signal "GND2")
		(14 "In6.Cu" signal "IN3")
		(16 "In7.Cu" signal "GND3")
		(18 "In8.Cu" signal "VCC")
		(20 "In9.Cu" signal "VCC1")
		(22 "In10.Cu" signal "GND4")
		(24 "In11.Cu" signal "IN4")
		(26 "In12.Cu" signal "GND5")
		(28 "In13.Cu" signal "IN5")
		(30 "In14.Cu" signal "GND6")
		(32 "In15.Cu" signal "IN6")
		(34 "In16.Cu" signal "GND7")
		(2 "B.Cu" signal "BOTTOM")
		(9 "F.Adhes" user "F.Adhesive")
		(11 "B.Adhes" user "B.Adhesive")
		(13 "F.Paste" user "Package Geometry/Pastemask Top")
		(15 "B.Paste" user "Package Geometry/Pastemask Bottom")
		(5 "F.SilkS" user "Ref Des/Silkscreen Top")
		(7 "B.SilkS" user "Ref Des/Silkscreen Bottom")
		(1 "F.Mask" user "Board Geometry/Soldermask Top")
		(3 "B.Mask" user "Board Geometry/Soldermask Bottom")
		(17 "Dwgs.User" user "User.Drawings")
		(19 "Cmts.User" user "User.Comments")
		(21 "Eco1.User" user "User.Eco1")
		(23 "Eco2.User" user "User.Eco2")
		(25 "Edge.Cuts" user "Board Geometry/Outline")
		(27 "Margin" user)
		(31 "F.CrtYd" user "Package Geometry/Place Bound Top")
		(29 "B.CrtYd" user "Package Geometry/Place Bound Bottom")
		(35 "F.Fab" user "Ref Des/Assembly Top")
		(33 "B.Fab" user "Ref Des/Assembly Bottom")
	)
	(footprint ""
		(layer "B.Cu")
		(at 119.083074 -324.990714 -90)
		(property "Reference" "PC572_P1_1"
			(at 0 0 90)
			(layer "B.SilkS")
			(hide yes)
			(effects
				(font
					(size 1.27 1.27)
				)
				(justify mirror)
			)
		)
		(property "Value" ""
			(at 0 0 90)
			(layer "B.Fab")
			(effects
				(font
					(size 1.27 1.27)
				)
				(justify mirror)
			)
		)
		(duplicate_pad_numbers_are_jumpers no)
		(fp_line
			(start -0.7874 0.4064)
			(end 0.7874 0.4064)
			(stroke
				(width 0.1524)
				(type default)
			)
			(layer "B.SilkS")
		)
		(fp_line
			(start 0.7874 0.4064)
			(end 0.7874 -0.4064)
			(stroke
				(width 0.1524)
				(type default)
			)
			(layer "B.SilkS")
		)
		(fp_line
			(start -0.7874 -0.4064)
			(end -0.7874 0.4064)
			(stroke
				(width 0.1524)
				(type default)
			)
			(layer "B.SilkS")
		)
		(fp_line
			(start 0.7874 -0.4064)
			(end -0.7874 -0.4064)
			(stroke
				(width 0.1524)
				(type default)
			)
			(layer "B.SilkS")
		)
		(fp_line
			(start -0.67945 0.3048)
			(end -0.120396 0.3048)
			(stroke
				(width 0.1)
				(type default)
			)
			(layer "B.Fab")
		)
		(fp_line
			(start -0.120396 0.3048)
			(end -0.120396 0.2794)
			(stroke
				(width 0.1)
				(type default)
			)
			(layer "B.Fab")
		)
		(fp_line
			(start 0.12065 0.3048)
			(end 0.67945 0.3048)
			(stroke
				(width 0.1)
				(type default)
			)
			(layer "B.Fab")
		)
		(fp_line
			(start 0.67945 0.3048)
			(end 0.67945 -0.305054)
			(stroke
				(width 0.1)
				(type default)
			)
			(layer "B.Fab")
		)
		(fp_line
			(start -0.120396 0.2794)
			(end 0.12065 0.2794)
			(stroke
				(width 0.1)
				(type default)
			)
			(layer "B.Fab")
		)
		(fp_line
			(start 0.12065 0.2794)
			(end 0.12065 0.3048)
			(stroke
				(width 0.1)
				(type default)
			)
			(layer "B.Fab")
		)
		(fp_line
			(start -0.12065 -0.2794)
			(end -0.12065 -0.3048)
			(stroke
				(width 0.1)
				(type default)
			)
			(layer "B.Fab")
		)
		(fp_line
			(start 0.12065 -0.2794)
			(end -0.12065 -0.2794)
			(stroke
				(width 0.1)
				(type default)
			)
			(layer "B.Fab")
		)
		(fp_line
			(start -0.67945 -0.3048)
			(end -0.67945 0.3048)
			(stroke
				(width 0.1)
				(type default)
			)
			(layer "B.Fab")
		)
		(fp_line
			(start -0.12065 -0.3048)
			(end -0.67945 -0.3048)
			(stroke
				(width 0.1)
				(type default)
			)
			(layer "B.Fab")
		)
		(fp_line
			(start 0.12065 -0.305054)
			(end 0.12065 -0.2794)
			(stroke
				(width 0.1)
				(type default)
			)
			(layer "B.Fab")
		)
		(fp_line
			(start 0.67945 -0.305054)
			(end 0.12065 -0.305054)
			(stroke
				(width 0.1)
				(type default)
			)
			(layer "B.Fab")
		)
		(pad "1" smd circle
			(at 0.40005 0 90)
			(size 0 0)
			(layers "B.Cu" "B.Mask" "B.Paste")
			(net "PVCCIN_CPU1")
		)
		(pad "2" smd circle
			(at -0.40005 0 90)
			(size 0 0)
			(layers "B.Cu" "B.Mask" "B.Paste")
			(net "GND")
		)
	)
	(footprint ""
		(layer "B.Cu")
		(at 19.588734 -176.423574 -90)
		(property "Reference" "R2385"
			(at 0 0 90)
			(layer "B.SilkS")
			(hide yes)
			(effects
				(font
					(size 1.27 1.27)
				)
				(justify mirror)
			)
		)
		(property "Value" ""
			(at 0 0 90)
			(layer "B.Fab")
			(effects
				(font
					(size 1.27 1.27)
				)
				(justify mirror)
			)
		)
		(duplicate_pad_numbers_are_jumpers no)
		(fp_line
			(start -0.7874 0.4064)
			(end 0.7874 0.4064)
			(stroke
				(width 0.1524)
				(type default)
			)
			(layer "B.SilkS")
		)
		(fp_line
			(start 0.7874 0.4064)
			(end 0.7874 -0.4064)
			(stroke
				(width 0.1524)
				(type default)
			)
			(layer "B.SilkS")
		)
		(fp_line
			(start -0.7874 -0.4064)
			(end -0.7874 0.4064)
			(stroke
				(width 0.1524)
				(type default)
			)
			(layer "B.SilkS")
		)
		(fp_line
			(start 0.7874 -0.4064)
			(end -0.7874 -0.4064)
			(stroke
				(width 0.1524)
				(type default)
			)
			(layer "B.SilkS")
		)
		(fp_line
			(start -0.67945 0.3048)
			(end -0.120396 0.3048)
			(stroke
				(width 0.1)
				(type default)
			)
			(layer "B.Fab")
		)
		(fp_line
			(start -0.120396 0.3048)
			(end -0.120396 0.2794)
			(stroke
				(width 0.1)
				(type default)
			)
			(layer "B.Fab")
		)
		(fp_line
			(start 0.12065 0.3048)
			(end 0.67945 0.3048)
			(stroke
				(width 0.1)
				(type default)
			)
			(layer "B.Fab")
		)
		(fp_line
			(start 0.67945 0.3048)
			(end 0.67945 -0.305054)
			(stroke
				(width 0.1)
				(type default)
			)
			(layer "B.Fab")
		)
		(fp_line
			(start -0.120396 0.2794)
			(end 0.12065 0.2794)
			(stroke
				(width 0.1)
				(type default)
			)
			(layer "B.Fab")
		)
		(fp_line
			(start 0.12065 0.2794)
			(end 0.12065 0.3048)
			(stroke
				(width 0.1)
				(type default)
			)
			(layer "B.Fab")
		)
		(fp_line
			(start -0.12065 -0.2794)
			(end -0.12065 -0.3048)
			(stroke
				(width 0.1)
				(type default)
			)
			(layer "B.Fab")
		)
		(fp_line
			(start 0.12065 -0.2794)
			(end -0.12065 -0.2794)
			(stroke
				(width 0.1)
				(type default)
			)
			(layer "B.Fab")
		)
		(fp_line
			(start -0.67945 -0.3048)
			(end -0.67945 0.3048)
			(stroke
				(width 0.1)
				(type default)
			)
			(layer "B.Fab")
		)
		(fp_line
			(start -0.12065 -0.3048)
			(end -0.67945 -0.3048)
			(stroke
				(width 0.1)
				(type default)
			)
			(layer "B.Fab")
		)
		(fp_line
			(start 0.12065 -0.305054)
			(end 0.12065 -0.2794)
			(stroke
				(width 0.1)
				(type default)
			)
			(layer "B.Fab")
		)
		(fp_line
			(start 0.67945 -0.305054)
			(end 0.12065 -0.305054)
			(stroke
				(width 0.1)
				(type default)
			)
			(layer "B.Fab")
		)
		(pad "1" smd circle
			(at 0.40005 0 90)
			(size 0 0)
			(layers "B.Cu" "B.Mask" "B.Paste")
			(net "FM_PVNN_MAIN_CPU1_EN")
		)
		(pad "2" smd circle
			(at -0.40005 0 90)
			(size 0 0)
			(layers "B.Cu" "B.Mask" "B.Paste")
			(net "GND")
		)
	)
)
